(kicad_pcb
	(version 20241229)
	(generator "pcbnew")
	(generator_version "9.0")
	(general
		(thickness 1.61)
		(legacy_teardrops no)
	)
	(paper "A3")
	(title_block
		(title "RDIMM DDR5 Tester")
		(date "2026-05-21")
		(rev "2.2.0")
		(company "Antmicro")
		(comment 9 "footprints 669-672 of 796")
	)
	(layers
		(0 "F.Cu" signal)
		(4 "In1.Cu" power)
		(6 "In2.Cu" mixed)
		(8 "In3.Cu" power)
		(10 "In4.Cu" mixed)
		(12 "In5.Cu" power)
		(14 "In6.Cu" mixed)
		(16 "In7.Cu" power)
		(18 "In8.Cu" power)
		(20 "In9.Cu" mixed)
		(22 "In10.Cu" power)
		(2 "B.Cu" signal)
		(9 "F.Adhes" user "F.Adhesive")
		(11 "B.Adhes" user "B.Adhesive")
		(13 "F.Paste" user)
		(15 "B.Paste" user)
		(5 "F.SilkS" user "F.Silkscreen")
		(7 "B.SilkS" user "B.Silkscreen")
		(1 "F.Mask" user)
		(3 "B.Mask" user)
		(17 "Dwgs.User" user "User.Drawings")
		(19 "Cmts.User" user "User.Comments")
		(21 "Eco1.User" user "User.Eco1")
		(23 "Eco2.User" user "User.Eco2")
		(25 "Edge.Cuts" user)
		(27 "Margin" user)
		(31 "F.CrtYd" user "F.Courtyard")
		(29 "B.CrtYd" user "B.Courtyard")
		(35 "F.Fab" user)
		(33 "B.Fab" user)
	)
	(footprint "antmicro-footprints:C_0402_1005Metric_EIA"
		(layer "B.Cu")
		(at 195.5 156)
		(descr "Capacitor SMD 0402 (1005 Metric), square (rectangular) end terminal, IPC_7351 nominal, (Body size source: IPC-SM-782 page 76, https://www.pcb-3d.com/wordpress/wp-content/uploads/ipc-sm-782a_amendment_1_and_2.pdf)")
		(tags "capacitor 0402")
		(property "Reference" "C76"
			(at -32.125 -10.4 0)
			(layer "B.SilkS")
			(effects
				(font
					(size 0.7 0.7)
					(thickness 0.15)
				)
				(justify right bottom mirror)
			)
		)
		(property "Value" "C_100n_0402"
			(at 0 -1.169 0)
			(layer "B.Fab")
			(effects
				(font
					(size 0.7 0.7)
					(thickness 0.15)
				)
				(justify right bottom mirror)
			)
		)
		(property "Datasheet" "https://www.murata.com/products/productdetail?partno=GRM155R61H104KE14%23"
			(at 0 0 0)
			(layer "F.Fab")
			(hide yes)
			(effects
				(font
					(size 1.27 1.27)
					(thickness 0.15)
				)
			)
		)
		(property "MPN" "GRM155R61H104KE14D"
			(at 0 0 0)
			(unlocked yes)
			(layer "B.Fab")
			(hide yes)
			(effects
				(font
					(size 1 1)
					(thickness 0.15)
				)
				(justify mirror)
			)
		)
		(property "Manufacturer" "Murata"
			(at 0 0 0)
			(unlocked yes)
			(layer "B.Fab")
			(hide yes)
			(effects
				(font
					(size 1 1)
					(thickness 0.15)
				)
				(justify mirror)
			)
		)
		(property "License" "Apache-2.0"
			(at 0 0 0)
			(unlocked yes)
			(layer "B.Fab")
			(hide yes)
			(effects
				(font
					(size 1 1)
					(thickness 0.15)
				)
				(justify mirror)
			)
		)
		(property "Author" "Antmicro"
			(at 0 0 0)
			(unlocked yes)
			(layer "B.Fab")
			(hide yes)
			(effects
				(font
					(size 1 1)
					(thickness 0.15)
				)
				(justify mirror)
			)
		)
		(property "Val" "100n"
			(at 0 0 0)
			(unlocked yes)
			(layer "B.Fab")
			(hide yes)
			(effects
				(font
					(size 1 1)
					(thickness 0.15)
				)
				(justify mirror)
			)
		)
		(property "Voltage" "50V"
			(at 0 0 0)
			(unlocked yes)
			(layer "B.Fab")
			(hide yes)
			(effects
				(font
					(size 1 1)
					(thickness 0.15)
				)
				(justify mirror)
			)
		)
		(property "Dielectric" "X5R"
			(at 0 0 0)
			(unlocked yes)
			(layer "B.Fab")
			(hide yes)
			(effects
				(font
					(size 1 1)
					(thickness 0.15)
				)
				(justify mirror)
			)
		)
		(sheetname "/FPGA power/")
		(sheetfile "fpga-power.kicad_sch")
		(attr smd)
		(fp_rect
			(start -0.95 0.45)
			(end 0.95 -0.45)
			(stroke
				(width 0.05)
				(type default)
			)
			(fill no)
			(layer "B.CrtYd")
		)
		(fp_line
			(start -0.5 -0.248)
			(end -0.5 0.25)
			(stroke
				(width 0.15)
				(type solid)
			)
			(layer "B.Fab")
		)
		(fp_line
			(start -0.5 0.25)
			(end 0.498 0.25)
			(stroke
				(width 0.15)
				(type solid)
			)
			(layer "B.Fab")
		)
		(fp_line
			(start 0.498 -0.248)
			(end -0.5 -0.248)
			(stroke
				(width 0.15)
				(type solid)
			)
			(layer "B.Fab")
		)
		(fp_line
			(start 0.498 0.25)
			(end 0.498 -0.248)
			(stroke
				(width 0.15)
				(type solid)
			)
			(layer "B.Fab")
		)
		(fp_text user "License: Apache-2.0"
			(at -0.9656 -4.369 180)
			(layer "B.Fab")
			(effects
				(font
					(size 0.7 0.7)
					(thickness 0.15)
				)
				(justify left bottom mirror)
			)
		)
		(fp_text user "${REFERENCE}"
			(at -0.9656 -3.169 180)
			(layer "B.Fab")
			(effects
				(font
					(size 0.7 0.7)
					(thickness 0.15)
				)
				(justify left bottom mirror)
			)
		)
		(fp_text user "Author: Antmicro"
			(at -0.9656 -5.569 180)
			(layer "B.Fab")
			(effects
				(font
					(size 0.7 0.7)
					(thickness 0.15)
				)
				(justify left bottom mirror)
			)
		)
		(pad "1" smd roundrect
			(at -0.5 0 270)
			(size 0.6 0.6)
			(layers "B.Cu" "B.Mask" "B.Paste")
			(roundrect_rratio 0.25)
			(net 1 "GND")
			(pintype "passive")
		)
		(pad "2" smd roundrect
			(at 0.498 0)
			(size 0.6 0.6)
			(layers "B.Cu" "B.Mask" "B.Paste")
			(roundrect_rratio 0.25)
			(net 797 "+1V8")
			(pintype "passive")
		)
	)
	(footprint "antmicro-footprints:SC70-3"
		(layer "B.Cu")
		(at 114.755 112.95 180)
		(property "Reference" "Q7"
			(at -3.355 -0.334 0)
			(layer "B.SilkS")
			(effects
				(font
					(size 0.7 0.7)
					(thickness 0.15)
				)
				(justify left bottom mirror)
			)
		)
		(property "Value" "BSS138PW"
			(at 0 -2.3 0)
			(layer "B.Fab")
			(effects
				(font
					(size 0.7 0.7)
					(thickness 0.15)
				)
				(justify left bottom mirror)
			)
		)
		(property "Datasheet" "https://assets.nexperia.com/documents/data-sheet/BSS138PW.pdf"
			(at 0 0 180)
			(layer "F.Fab")
			(hide yes)
			(effects
				(font
					(size 1.27 1.27)
					(thickness 0.15)
				)
			)
		)
		(property "MPN" "BSS138PW"
			(at 0 0 180)
			(unlocked yes)
			(layer "B.Fab")
			(hide yes)
			(effects
				(font
					(size 1 1)
					(thickness 0.15)
				)
				(justify mirror)
			)
		)
		(property "Manufacturer" "Nexperia"
			(at 0 0 180)
			(unlocked yes)
			(layer "B.Fab")
			(hide yes)
			(effects
				(font
					(size 1 1)
					(thickness 0.15)
				)
				(justify mirror)
			)
		)
		(property "Author" "Antmicro"
			(at 0 0 180)
			(unlocked yes)
			(layer "B.Fab")
			(hide yes)
			(effects
				(font
					(size 1 1)
					(thickness 0.15)
				)
				(justify mirror)
			)
		)
		(property "License" "Apache-2.0"
			(at 0 0 180)
			(unlocked yes)
			(layer "B.Fab")
			(hide yes)
			(effects
				(font
					(size 1 1)
					(thickness 0.15)
				)
				(justify mirror)
			)
		)
		(sheetname "/FPGA banks HD/")
		(sheetfile "fpga-hd-banks.kicad_sch")
		(attr smd)
		(fp_line
			(start 0.627 0.6)
			(end 0.627 0.999)
			(stroke
				(width 0.15)
				(type solid)
			)
			(layer "B.SilkS")
		)
		(fp_line
			(start 0.627 -0.6)
			(end 0.627 -1.001)
			(stroke
				(width 0.15)
				(type solid)
			)
			(layer "B.SilkS")
		)
		(fp_line
			(start -0.3 1)
			(end 0.627 0.999)
			(stroke
				(width 0.15)
				(type solid)
			)
			(layer "B.SilkS")
		)
		(fp_line
			(start -0.3 -1)
			(end 0.627 -1.001)
			(stroke
				(width 0.15)
				(type solid)
			)
			(layer "B.SilkS")
		)
		(fp_line
			(start 1.4 0.4)
			(end 1.4 -0.4)
			(stroke
				(width 0.05)
				(type solid)
			)
			(layer "B.CrtYd")
		)
		(fp_line
			(start 1.4 -0.4)
			(end 0.9 -0.4)
			(stroke
				(width 0.05)
				(type solid)
			)
			(layer "B.CrtYd")
		)
		(fp_line
			(start 0.9 1.3)
			(end 0.9 0.4)
			(stroke
				(width 0.05)
				(type solid)
			)
			(layer "B.CrtYd")
		)
		(fp_line
			(start 0.9 0.4)
			(end 1.4 0.4)
			(stroke
				(width 0.05)
				(type solid)
			)
			(layer "B.CrtYd")
		)
		(fp_line
			(start 0.9 -0.4)
			(end 0.9 -1.3)
			(stroke
				(width 0.05)
				(type solid)
			)
			(layer "B.CrtYd")
		)
		(fp_line
			(start 0.9 -1.3)
			(end -0.9 -1.3)
			(stroke
				(width 0.05)
				(type solid)
			)
			(layer "B.CrtYd")
		)
		(fp_line
			(start -0.9 1.3)
			(end 0.9 1.3)
			(stroke
				(width 0.05)
				(type solid)
			)
			(layer "B.CrtYd")
		)
		(fp_line
			(start -0.9 1.3)
			(end -0.9 1)
			(stroke
				(width 0.05)
				(type solid)
			)
			(layer "B.CrtYd")
		)
		(fp_line
			(start -0.9 1)
			(end -1.4 1)
			(stroke
				(width 0.05)
				(type solid)
			)
			(layer "B.CrtYd")
		)
		(fp_line
			(start -0.9 -1)
			(end -1.4 -1)
			(stroke
				(width 0.05)
				(type solid)
			)
			(layer "B.CrtYd")
		)
		(fp_line
			(start -0.9 -1.3)
			(end -0.9 -1)
			(stroke
				(width 0.05)
				(type solid)
			)
			(layer "B.CrtYd")
		)
		(fp_line
			(start -1.4 -1)
			(end -1.4 1)
			(stroke
				(width 0.05)
				(type solid)
			)
			(layer "B.CrtYd")
		)
		(fp_rect
			(start -0.623 0.999)
			(end 0.627 -1.001)
			(stroke
				(width 0.15)
				(type solid)
			)
			(fill no)
			(layer "B.Fab")
		)
		(fp_text user "License: Apache-2.0"
			(at -1.45 -6.782 0)
			(layer "B.Fab")
			(effects
				(font
					(size 0.7 0.7)
					(thickness 0.15)
				)
				(justify left bottom mirror)
			)
		)
		(fp_text user "${REFERENCE}"
			(at -1.45 -4.783 0)
			(layer "B.Fab")
			(effects
				(font
					(size 0.7 0.7)
					(thickness 0.15)
				)
				(justify left bottom mirror)
			)
		)
		(fp_text user "Author: Antmicro"
			(at -1.45 -5.782 0)
			(layer "B.Fab")
			(effects
				(font
					(size 0.7 0.7)
					(thickness 0.15)
				)
				(justify left bottom mirror)
			)
		)
		(pad "1" smd rect
			(at -1.051 0.65 90)
			(size 0.6 0.6)
			(layers "B.Cu" "B.Mask" "B.Paste")
			(net 698 "/FPGA banks HD/USR_LED2")
			(pinfunction "G")
			(pintype "passive")
		)
		(pad "2" smd rect
			(at -1.051 -0.65 90)
			(size 0.6 0.6)
			(layers "B.Cu" "B.Mask" "B.Paste")
			(net 1 "GND")
			(pinfunction "S")
			(pintype "passive")
		)
		(pad "3" smd rect
			(at 1.05 0 90)
			(size 0.6 0.6)
			(layers "B.Cu" "B.Mask" "B.Paste")
			(net 275 "Net-(Q7-D)")
			(pinfunction "D")
			(pintype "passive")
		)
	)
	(footprint "antmicro-footprints:C_0402_1005Metric_EIA"
		(layer "B.Cu")
		(at 193 148.5 -90)
		(descr "Capacitor SMD 0402 (1005 Metric), square (rectangular) end terminal, IPC_7351 nominal, (Body size source: IPC-SM-782 page 76, https://www.pcb-3d.com/wordpress/wp-content/uploads/ipc-sm-782a_amendment_1_and_2.pdf)")
		(tags "capacitor 0402")
		(property "Reference" "C84"
			(at -12.375 30.65 90)
			(layer "B.SilkS")
			(effects
				(font
					(size 0.7 0.7)
					(thickness 0.15)
				)
				(justify left bottom mirror)
			)
		)
		(property "Value" "C_1u_25V_0402"
			(at 0 -1.169 90)
			(layer "B.Fab")
			(effects
				(font
					(size 0.7 0.7)
					(thickness 0.15)
				)
				(justify left bottom mirror)
			)
		)
		(property "Datasheet" "https://www.murata.com/products/productdetail?partno=GRM155R61E105KE11%23"
			(at 0 0 270)
			(layer "F.Fab")
			(hide yes)
			(effects
				(font
					(size 1.27 1.27)
					(thickness 0.15)
				)
			)
		)
		(property "MPN" "GRM155R61E105KE11J"
			(at 0 0 270)
			(unlocked yes)
			(layer "B.Fab")
			(hide yes)
			(effects
				(font
					(size 1 1)
					(thickness 0.15)
				)
				(justify mirror)
			)
		)
		(property "Manufacturer" "Murata"
			(at 0 0 270)
			(unlocked yes)
			(layer "B.Fab")
			(hide yes)
			(effects
				(font
					(size 1 1)
					(thickness 0.15)
				)
				(justify mirror)
			)
		)
		(property "License" "Apache-2.0"
			(at 0 0 270)
			(unlocked yes)
			(layer "B.Fab")
			(hide yes)
			(effects
				(font
					(size 1 1)
					(thickness 0.15)
				)
				(justify mirror)
			)
		)
		(property "Author" "Antmicro"
			(at 0 0 270)
			(unlocked yes)
			(layer "B.Fab")
			(hide yes)
			(effects
				(font
					(size 1 1)
					(thickness 0.15)
				)
				(justify mirror)
			)
		)
		(property "Val" "1u"
			(at 0 0 270)
			(unlocked yes)
			(layer "B.Fab")
			(hide yes)
			(effects
				(font
					(size 1 1)
					(thickness 0.15)
				)
				(justify mirror)
			)
		)
		(property "Voltage" "25V"
			(at 0 0 270)
			(unlocked yes)
			(layer "B.Fab")
			(hide yes)
			(effects
				(font
					(size 1 1)
					(thickness 0.15)
				)
				(justify mirror)
			)
		)
		(property "Dielectric" "X5R"
			(at 0 0 270)
			(unlocked yes)
			(layer "B.Fab")
			(hide yes)
			(effects
				(font
					(size 1 1)
					(thickness 0.15)
				)
				(justify mirror)
			)
		)
		(sheetname "/FPGA power/")
		(sheetfile "fpga-power.kicad_sch")
		(attr smd)
		(fp_rect
			(start -0.95 0.45)
			(end 0.95 -0.45)
			(stroke
				(width 0.05)
				(type default)
			)
			(fill no)
			(layer "B.CrtYd")
		)
		(fp_line
			(start -0.5 0.25)
			(end 0.498 0.25)
			(stroke
				(width 0.15)
				(type solid)
			)
			(layer "B.Fab")
		)
		(fp_line
			(start 0.498 0.25)
			(end 0.498 -0.248)
			(stroke
				(width 0.15)
				(type solid)
			)
			(layer "B.Fab")
		)
		(fp_line
			(start -0.5 -0.248)
			(end -0.5 0.25)
			(stroke
				(width 0.15)
				(type solid)
			)
			(layer "B.Fab")
		)
		(fp_line
			(start 0.498 -0.248)
			(end -0.5 -0.248)
			(stroke
				(width 0.15)
				(type solid)
			)
			(layer "B.Fab")
		)
		(fp_text user "Author: Antmicro"
			(at -0.9656 -5.569 90)
			(layer "B.Fab")
			(effects
				(font
					(size 0.7 0.7)
					(thickness 0.15)
				)
				(justify left bottom mirror)
			)
		)
		(fp_text user "${REFERENCE}"
			(at -0.9656 -3.169 90)
			(layer "B.Fab")
			(effects
				(font
					(size 0.7 0.7)
					(thickness 0.15)
				)
				(justify left bottom mirror)
			)
		)
		(fp_text user "License: Apache-2.0"
			(at -0.9656 -4.369 90)
			(layer "B.Fab")
			(effects
				(font
					(size 0.7 0.7)
					(thickness 0.15)
				)
				(justify left bottom mirror)
			)
		)
		(pad "1" smd roundrect
			(at -0.5 0 180)
			(size 0.6 0.6)
			(layers "B.Cu" "B.Mask" "B.Paste")
			(roundrect_rratio 0.25)
			(net 1 "GND")
			(pintype "passive")
		)
		(pad "2" smd roundrect
			(at 0.498 0 270)
			(size 0.6 0.6)
			(layers "B.Cu" "B.Mask" "B.Paste")
			(roundrect_rratio 0.25)
			(net 553 "+0V85")
			(pintype "passive")
		)
	)
	(footprint "antmicro-footprints:R_0402_1005Metric"
		(layer "B.Cu")
		(at 219.91 151.85 180)
		(descr "Resistor SMD 0402")
		(tags "resistor SMD 0402")
		(property "Reference" "R5"
			(at -2.51 -0.48 0)
			(layer "B.SilkS")
			(effects
				(font
					(size 0.7 0.7)
					(thickness 0.15)
				)
				(justify left bottom mirror)
			)
		)
		(property "Value" "R_4k7_0402"
			(at 6.885407 -0.258797 0)
			(layer "B.Fab")
			(effects
				(font
					(size 0.7 0.7)
					(thickness 0.15)
				)
				(justify left bottom mirror)
			)
		)
		(property "Datasheet" "https://www.bourns.com/docs/product-datasheets/cr.pdf"
			(at 0 0 180)
			(layer "F.Fab")
			(hide yes)
			(effects
				(font
					(size 1.27 1.27)
					(thickness 0.15)
				)
			)
		)
		(property "Manufacturer" "Bourns"
			(at 0 0 180)
			(unlocked yes)
			(layer "B.Fab")
			(hide yes)
			(effects
				(font
					(size 1 1)
					(thickness 0.15)
				)
				(justify mirror)
			)
		)
		(property "MPN" "CR0402-FX-4701GLF"
			(at 0 0 180)
			(unlocked yes)
			(layer "B.Fab")
			(hide yes)
			(effects
				(font
					(size 1 1)
					(thickness 0.15)
				)
				(justify mirror)
			)
		)
		(property "Val" "4k7"
			(at 0 0 180)
			(unlocked yes)
			(layer "B.Fab")
			(hide yes)
			(effects
				(font
					(size 1 1)
					(thickness 0.15)
				)
				(justify mirror)
			)
		)
		(property "License" "Apache-2.0"
			(at 0 0 180)
			(unlocked yes)
			(layer "B.Fab")
			(hide yes)
			(effects
				(font
					(size 1 1)
					(thickness 0.15)
				)
				(justify mirror)
			)
		)
		(property "Author" "Antmicro"
			(at 0 0 180)
			(unlocked yes)
			(layer "B.Fab")
			(hide yes)
			(effects
				(font
					(size 1 1)
					(thickness 0.15)
				)
				(justify mirror)
			)
		)
		(property "Tolerance" "1%"
			(at 0 0 180)
			(unlocked yes)
			(layer "B.Fab")
			(hide yes)
			(effects
				(font
					(size 1 1)
					(thickness 0.15)
				)
				(justify mirror)
			)
		)
		(sheetname "/HyperRAM + QSPI Flash/")
		(sheetfile "hyperram-flash.kicad_sch")
		(attr smd)
		(fp_rect
			(start -0.925 0.47)
			(end 0.925 -0.47)
			(stroke
				(width 0.05)
				(type default)
			)
			(fill no)
			(layer "B.CrtYd")
		)
		(fp_rect
			(start -0.5 0.25)
			(end 0.5 -0.25)
			(stroke
				(width 0.15)
				(type solid)
			)
			(fill no)
			(layer "B.Fab")
		)
		(fp_text user "Author: Antmicro"
			(at -0.95 -4.169 0)
			(layer "B.Fab")
			(effects
				(font
					(size 0.7 0.7)
					(thickness 0.15)
				)
				(justify left bottom mirror)
			)
		)
		(fp_text user "${REFERENCE}"
			(at -0.95 -3.168 0)
			(layer "B.Fab")
			(effects
				(font
					(size 0.7 0.7)
					(thickness 0.15)
				)
				(justify left bottom mirror)
			)
		)
		(fp_text user "License: Apache-2.0"
			(at -0.95 -5.169 0)
			(layer "B.Fab")
			(effects
				(font
					(size 0.7 0.7)
					(thickness 0.15)
				)
				(justify left bottom mirror)
			)
		)
		(pad "1" smd roundrect
			(at -0.48 0 180)
			(size 0.59 0.64)
			(layers "B.Cu" "B.Mask" "B.Paste")
			(roundrect_rratio 0.25)
			(net 797 "+1V8")
			(pintype "passive")
		)
		(pad "2" smd roundrect
			(at 0.48 0 180)
			(size 0.59 0.64)
			(layers "B.Cu" "B.Mask" "B.Paste")
			(roundrect_rratio 0.25)
			(net 280 "/HyperRAM + QSPI Flash/IO2")
			(pintype "passive")
		)
	)
)
